FILE_TYPE = MACRO_DRAWING;
SET COLOR_WIRE YELLOW;
SET COLOR_PROP ORANGE;
SET COLOR_DOT WHITE;
SET COLOR_ARC YELLOW;
SET COLOR_BODY GREEN;
SET COLOR_NOTE PURPLE;
SET PROP_DISPLAY VALUE;
SET PAGE_NUMBER P459;
FORCEADD PT5161LRS..6
(-7625 4400);
FORCEPROP 1 LAST LOCATION U6017
J 0
(-7975 6025);
DISPLAY 0.723404 (-7975 6025);
PAINT GREEN (-7975 6025);
FORCEPROP 0 LAST $SEC 6
J 0
(-7975 6175);
DISPLAY 0.680851 (-7975 6175);
PAINT MONO (-7975 6175);
DISPLAY INVISIBLE (-7975 6175);
FORCEPROP 0 LAST CDS_SEC 6
J 0
(-7975 6175);
DISPLAY 0.680851 (-7975 6175);
DISPLAY INVISIBLE (-7975 6175);
FORCEPROP 0 LASTPIN (-7175 5550) $PN P29
J 0
(-7165 5560);
DISPLAY 0.680851 (-7165 5560);
PAINT MONO (-7165 5560);
FORCEPROP 0 LASTPIN (-7175 5200) $PN AA29
J 0
(-7165 5210);
DISPLAY 0.680851 (-7165 5210);
PAINT MONO (-7165 5210);
FORCEPROP 0 LASTPIN (-7175 4850) $PN AH29
J 0
(-7165 4860);
DISPLAY 0.680851 (-7165 4860);
PAINT MONO (-7165 4860);
FORCEPROP 0 LASTPIN (-7175 4500) $PN AR29
J 0
(-7165 4510);
DISPLAY 0.680851 (-7165 4510);
PAINT MONO (-7165 4510);
FORCEPROP 0 LASTPIN (-7175 4150) $PN BB29
J 0
(-7165 4160);
DISPLAY 0.680851 (-7165 4160);
PAINT MONO (-7165 4160);
FORCEPROP 0 LASTPIN (-7175 3800) $PN BJ29
J 0
(-7165 3810);
DISPLAY 0.680851 (-7165 3810);
PAINT MONO (-7165 3810);
FORCEPROP 0 LASTPIN (-7175 3450) $PN BT29
J 0
(-7165 3460);
DISPLAY 0.680851 (-7165 3460);
PAINT MONO (-7165 3460);
FORCEPROP 0 LASTPIN (-7175 3100) $PN CC29
J 0
(-7165 3110);
DISPLAY 0.680851 (-7165 3110);
PAINT MONO (-7165 3110);
FORCEPROP 0 LASTPIN (-7175 5650) $PN M26
J 0
(-7165 5660);
DISPLAY 0.680851 (-7165 5660);
PAINT MONO (-7165 5660);
FORCEPROP 0 LASTPIN (-7175 5300) $PN W26
J 0
(-7165 5310);
DISPLAY 0.680851 (-7165 5310);
PAINT MONO (-7165 5310);
FORCEPROP 0 LASTPIN (-7175 4950) $PN AF26
J 0
(-7165 4960);
DISPLAY 0.680851 (-7165 4960);
PAINT MONO (-7165 4960);
FORCEPROP 0 LASTPIN (-7175 4600) $PN AN26
J 0
(-7165 4610);
DISPLAY 0.680851 (-7165 4610);
PAINT MONO (-7165 4610);
FORCEPROP 0 LASTPIN (-7175 4250) $PN AY26
J 0
(-7165 4260);
DISPLAY 0.680851 (-7165 4260);
PAINT MONO (-7165 4260);
FORCEPROP 0 LASTPIN (-7175 3900) $PN BG26
J 0
(-7165 3910);
DISPLAY 0.680851 (-7165 3910);
PAINT MONO (-7165 3910);
FORCEPROP 0 LASTPIN (-7175 3550) $PN BP26
J 0
(-7165 3560);
DISPLAY 0.680851 (-7165 3560);
PAINT MONO (-7165 3560);
FORCEPROP 0 LASTPIN (-7175 3200) $PN CA26
J 0
(-7165 3210);
DISPLAY 0.680851 (-7165 3210);
PAINT MONO (-7165 3210);
FORCEPROP 2 LAST VALUE PT5161LRS
J 0
(-7975 6075);
DISPLAY 0.680851 (-7975 6075);
FORCEPROP 1 LAST MATERIAL IC
J 0
(-7975 5875);
DISPLAY 0.723404 (-7975 5875);
PAINT GREEN (-7975 5875);
FORCEPROP 2 LAST PART_TYPE SMLF
J 0
(-7975 6125);
DISPLAY 0.680851 (-7975 6125);
FORCEPROP 2 LAST CDS_LIB pure_quanta
J 0
(-7625 4400);
DISPLAY INVISIBLE (-7625 4400);
FORCEPROP 1 LAST CDS_LMAN_SYM_OUTLINE -350,1450,300,-1400
J 0
(-7625 4400);
DISPLAY 0.468085 (-7625 4400);
PAINT GREEN (-7625 4400);
DISPLAY INVISIBLE (-7625 4400);
FORCEPROP 1 LAST NEEDS_NO_SIZE TRUE
J 0
(-7625 4400);
DISPLAY 0.723404 (-7625 4400);
PAINT GREEN (-7625 4400);
DISPLAY INVISIBLE (-7625 4400);
FORCEPROP 1 LAST PATH I1
J 0
(-7625 4400);
DISPLAY 0.723404 (-7625 4400);
PAINT GREEN (-7625 4400);
DISPLAY INVISIBLE (-7625 4400);
FORCEPROP 1 LAST PART_NUMBER AJ051610U03
J 0
(-7975 5950);
DISPLAY 0.723404 (-7975 5950);
PAINT GREEN (-7975 5950);
DISPLAY INVISIBLE (-7975 5950);
FORCEADD TAP..1
(-6400 4150);
FORCEPROP 3 LASTPIN (-6450 4150) SIG_NAME P5E_CPU1_P3_RX_DN<11>
J 0
(-6440 4160);
DISPLAY 0.659574 (-6440 4160);
PAINT MONO (-6440 4160);
DISPLAY INVISIBLE (-6440 4160);
FORCEPROP 1 LASTPIN (-6450 4150) BN 11
J 0
(-6462 4158);
DISPLAY 0.680851 (-6462 4158);
PAINT GREEN (-6462 4158);
FORCEPROP 2 LAST CDS_LIB standard
J 0
(-6400 4150);
DISPLAY INVISIBLE (-6400 4150);
FORCEPROP 1 LAST BODY_TYPE PLUMBING
J 0
(-6400 4200);
DISPLAY 0.872340 (-6400 4200);
PAINT GREEN (-6400 4200);
DISPLAY INVISIBLE (-6400 4200);
FORCEPROP 1 LAST HDL_TAP TRUE
J 0
(-6075 4025);
DISPLAY 0.872340 (-6075 4025);
DISPLAY INVISIBLE (-6075 4025);
FORCEPROP 1 LAST PATH I10
J 0
(-6402 4150);
DISPLAY 0.872340 (-6402 4150);
PAINT GREEN (-6402 4150);
DISPLAY INVISIBLE (-6402 4150);
FORCEADD TAP..1
(-6400 4500);
FORCEPROP 3 LASTPIN (-6450 4500) SIG_NAME P5E_CPU1_P3_RX_DN<12>
J 0
(-6440 4510);
DISPLAY 0.659574 (-6440 4510);
PAINT MONO (-6440 4510);
DISPLAY INVISIBLE (-6440 4510);
FORCEPROP 1 LASTPIN (-6450 4500) BN 12
J 0
(-6462 4508);
DISPLAY 0.680851 (-6462 4508);
PAINT GREEN (-6462 4508);
FORCEPROP 2 LAST CDS_LIB standard
J 0
(-6400 4500);
DISPLAY INVISIBLE (-6400 4500);
FORCEPROP 1 LAST BODY_TYPE PLUMBING
J 0
(-6400 4550);
DISPLAY 0.872340 (-6400 4550);
PAINT GREEN (-6400 4550);
DISPLAY INVISIBLE (-6400 4550);
FORCEPROP 1 LAST HDL_TAP TRUE
J 0
(-6075 4375);
DISPLAY 0.872340 (-6075 4375);
DISPLAY INVISIBLE (-6075 4375);
FORCEPROP 1 LAST PATH I11
J 0
(-6402 4500);
DISPLAY 0.872340 (-6402 4500);
PAINT GREEN (-6402 4500);
DISPLAY INVISIBLE (-6402 4500);
FORCEADD TAP..1
(-6600 4950);
FORCEPROP 3 LASTPIN (-6650 4950) SIG_NAME P5E_CPU1_P3_RX_DP<13>
J 0
(-6640 4960);
DISPLAY 0.659574 (-6640 4960);
PAINT MONO (-6640 4960);
DISPLAY INVISIBLE (-6640 4960);
FORCEPROP 1 LASTPIN (-6650 4950) BN 13
J 0
(-6662 4958);
DISPLAY 0.680851 (-6662 4958);
PAINT GREEN (-6662 4958);
FORCEPROP 2 LAST CDS_LIB standard
J 0
(-6600 4950);
DISPLAY INVISIBLE (-6600 4950);
FORCEPROP 1 LAST BODY_TYPE PLUMBING
J 0
(-6600 5000);
DISPLAY 0.872340 (-6600 5000);
PAINT GREEN (-6600 5000);
DISPLAY INVISIBLE (-6600 5000);
FORCEPROP 1 LAST HDL_TAP TRUE
J 0
(-6275 4825);
DISPLAY 0.872340 (-6275 4825);
DISPLAY INVISIBLE (-6275 4825);
FORCEPROP 1 LAST PATH I12
J 0
(-6602 4950);
DISPLAY 0.872340 (-6602 4950);
PAINT GREEN (-6602 4950);
DISPLAY INVISIBLE (-6602 4950);
FORCEADD TAP..1
(-6600 5300);
FORCEPROP 3 LASTPIN (-6650 5300) SIG_NAME P5E_CPU1_P3_RX_DP<14>
J 0
(-6640 5310);
DISPLAY 0.659574 (-6640 5310);
PAINT MONO (-6640 5310);
DISPLAY INVISIBLE (-6640 5310);
FORCEPROP 1 LASTPIN (-6650 5300) BN 14
J 0
(-6662 5308);
DISPLAY 0.680851 (-6662 5308);
PAINT GREEN (-6662 5308);
FORCEPROP 2 LAST CDS_LIB standard
J 0
(-6600 5300);
DISPLAY INVISIBLE (-6600 5300);
FORCEPROP 1 LAST BODY_TYPE PLUMBING
J 0
(-6600 5350);
DISPLAY 0.872340 (-6600 5350);
PAINT GREEN (-6600 5350);
DISPLAY INVISIBLE (-6600 5350);
FORCEPROP 1 LAST HDL_TAP TRUE
J 0
(-6275 5175);
DISPLAY 0.872340 (-6275 5175);
DISPLAY INVISIBLE (-6275 5175);
FORCEPROP 1 LAST PATH I13
J 0
(-6602 5300);
DISPLAY 0.872340 (-6602 5300);
PAINT GREEN (-6602 5300);
DISPLAY INVISIBLE (-6602 5300);
FORCEADD TAP..1
(-6600 5650);
FORCEPROP 3 LASTPIN (-6650 5650) SIG_NAME P5E_CPU1_P3_RX_DP<15>
J 0
(-6640 5660);
DISPLAY 0.659574 (-6640 5660);
PAINT MONO (-6640 5660);
DISPLAY INVISIBLE (-6640 5660);
FORCEPROP 1 LASTPIN (-6650 5650) BN 15
J 0
(-6662 5658);
DISPLAY 0.680851 (-6662 5658);
PAINT GREEN (-6662 5658);
FORCEPROP 2 LAST CDS_LIB standard
J 0
(-6600 5650);
DISPLAY INVISIBLE (-6600 5650);
FORCEPROP 1 LAST BODY_TYPE PLUMBING
J 0
(-6600 5700);
DISPLAY 0.872340 (-6600 5700);
PAINT GREEN (-6600 5700);
DISPLAY INVISIBLE (-6600 5700);
FORCEPROP 1 LAST HDL_TAP TRUE
J 0
(-6275 5525);
DISPLAY 0.872340 (-6275 5525);
DISPLAY INVISIBLE (-6275 5525);
FORCEPROP 1 LAST PATH I14
J 0
(-6602 5650);
DISPLAY 0.872340 (-6602 5650);
PAINT GREEN (-6602 5650);
DISPLAY INVISIBLE (-6602 5650);
FORCEADD TAP..1
(-6400 4850);
FORCEPROP 3 LASTPIN (-6450 4850) SIG_NAME P5E_CPU1_P3_RX_DN<13>
J 0
(-6440 4860);
DISPLAY 0.659574 (-6440 4860);
PAINT MONO (-6440 4860);
DISPLAY INVISIBLE (-6440 4860);
FORCEPROP 1 LASTPIN (-6450 4850) BN 13
J 0
(-6462 4858);
DISPLAY 0.680851 (-6462 4858);
PAINT GREEN (-6462 4858);
FORCEPROP 2 LAST CDS_LIB standard
J 0
(-6400 4850);
DISPLAY INVISIBLE (-6400 4850);
FORCEPROP 1 LAST BODY_TYPE PLUMBING
J 0
(-6400 4900);
DISPLAY 0.872340 (-6400 4900);
PAINT GREEN (-6400 4900);
DISPLAY INVISIBLE (-6400 4900);
FORCEPROP 1 LAST HDL_TAP TRUE
J 0
(-6075 4725);
DISPLAY 0.872340 (-6075 4725);
DISPLAY INVISIBLE (-6075 4725);
FORCEPROP 1 LAST PATH I15
J 0
(-6402 4850);
DISPLAY 0.872340 (-6402 4850);
PAINT GREEN (-6402 4850);
DISPLAY INVISIBLE (-6402 4850);
FORCEADD TAP..1
(-6400 5200);
FORCEPROP 3 LASTPIN (-6450 5200) SIG_NAME P5E_CPU1_P3_RX_DN<14>
J 0
(-6440 5210);
DISPLAY 0.659574 (-6440 5210);
PAINT MONO (-6440 5210);
DISPLAY INVISIBLE (-6440 5210);
FORCEPROP 1 LASTPIN (-6450 5200) BN 14
J 0
(-6462 5208);
DISPLAY 0.680851 (-6462 5208);
PAINT GREEN (-6462 5208);
FORCEPROP 2 LAST CDS_LIB standard
J 0
(-6400 5200);
DISPLAY INVISIBLE (-6400 5200);
FORCEPROP 1 LAST BODY_TYPE PLUMBING
J 0
(-6400 5250);
DISPLAY 0.872340 (-6400 5250);
PAINT GREEN (-6400 5250);
DISPLAY INVISIBLE (-6400 5250);
FORCEPROP 1 LAST HDL_TAP TRUE
J 0
(-6075 5075);
DISPLAY 0.872340 (-6075 5075);
DISPLAY INVISIBLE (-6075 5075);
FORCEPROP 1 LAST PATH I16
J 0
(-6402 5200);
DISPLAY 0.872340 (-6402 5200);
PAINT GREEN (-6402 5200);
DISPLAY INVISIBLE (-6402 5200);
FORCEADD TAP..1
(-6400 5550);
FORCEPROP 3 LASTPIN (-6450 5550) SIG_NAME P5E_CPU1_P3_RX_DN<15>
J 0
(-6440 5560);
DISPLAY 0.659574 (-6440 5560);
PAINT MONO (-6440 5560);
DISPLAY INVISIBLE (-6440 5560);
FORCEPROP 1 LASTPIN (-6450 5550) BN 15
J 0
(-6462 5558);
DISPLAY 0.680851 (-6462 5558);
PAINT GREEN (-6462 5558);
FORCEPROP 2 LAST CDS_LIB standard
J 0
(-6400 5550);
DISPLAY INVISIBLE (-6400 5550);
FORCEPROP 1 LAST BODY_TYPE PLUMBING
J 0
(-6400 5600);
DISPLAY 0.872340 (-6400 5600);
PAINT GREEN (-6400 5600);
DISPLAY INVISIBLE (-6400 5600);
FORCEPROP 1 LAST HDL_TAP TRUE
J 0
(-6075 5425);
DISPLAY 0.872340 (-6075 5425);
DISPLAY INVISIBLE (-6075 5425);
FORCEPROP 1 LAST PATH I17
J 0
(-6402 5550);
DISPLAY 0.872340 (-6402 5550);
PAINT GREEN (-6402 5550);
DISPLAY INVISIBLE (-6402 5550);
FORCEADD OFFPAGE..5
R 2
(-5400 5625);
FORCEPROP 2 LAST $XR0 52 
J 0
(-5211 5625);
DISPLAY 0.638298 (-5211 5625);
PAINT MONO (-5211 5625);
FORCEPROP 2 LAST CDS_LIB standard
J 0
(-5400 5625);
DISPLAY INVISIBLE (-5400 5625);
FORCEPROP 1 LAST OFFPAGE TRUE
J 2
(-5725 5500);
DISPLAY 0.872340 (-5725 5500);
PAINT GREEN (-5725 5500);
DISPLAY INVISIBLE (-5725 5500);
FORCEPROP 1 LAST COMMENT_BODY TRUE
J 2
(-5500 5550);
DISPLAY 0.872340 (-5500 5550);
PAINT GREEN (-5500 5550);
DISPLAY INVISIBLE (-5500 5550);
FORCEPROP 2 LAST PATH I18
J 0
(-5225 5700);
DISPLAY 0.680851 (-5225 5700);
DISPLAY INVISIBLE (-5225 5700);
FORCEADD OFFPAGE..5
R 2
(-5375 5750);
FORCEPROP 2 LAST $XR0 52 
J 0
(-5186 5750);
DISPLAY 0.638298 (-5186 5750);
PAINT MONO (-5186 5750);
FORCEPROP 2 LAST CDS_LIB standard
J 0
(-5375 5750);
DISPLAY INVISIBLE (-5375 5750);
FORCEPROP 1 LAST OFFPAGE TRUE
J 2
(-5700 5625);
DISPLAY 0.872340 (-5700 5625);
PAINT GREEN (-5700 5625);
DISPLAY INVISIBLE (-5700 5625);
FORCEPROP 1 LAST COMMENT_BODY TRUE
J 2
(-5475 5675);
DISPLAY 0.872340 (-5475 5675);
PAINT GREEN (-5475 5675);
DISPLAY INVISIBLE (-5475 5675);
FORCEPROP 2 LAST PATH I19
J 0
(-5200 5825);
DISPLAY 0.680851 (-5200 5825);
DISPLAY INVISIBLE (-5200 5825);
FORCEADD TAP..1
(-6600 3200);
FORCEPROP 3 LASTPIN (-6650 3200) SIG_NAME P5E_CPU1_P3_RX_DP<8>
J 0
(-6640 3210);
DISPLAY 0.659574 (-6640 3210);
PAINT MONO (-6640 3210);
DISPLAY INVISIBLE (-6640 3210);
FORCEPROP 1 LASTPIN (-6650 3200) BN 8
J 0
(-6662 3208);
DISPLAY 0.680851 (-6662 3208);
PAINT GREEN (-6662 3208);
FORCEPROP 2 LAST CDS_LIB standard
J 0
(-6600 3200);
DISPLAY INVISIBLE (-6600 3200);
FORCEPROP 1 LAST BODY_TYPE PLUMBING
J 0
(-6600 3250);
DISPLAY 0.872340 (-6600 3250);
PAINT GREEN (-6600 3250);
DISPLAY INVISIBLE (-6600 3250);
FORCEPROP 1 LAST HDL_TAP TRUE
J 0
(-6275 3075);
DISPLAY 0.872340 (-6275 3075);
DISPLAY INVISIBLE (-6275 3075);
FORCEPROP 1 LAST PATH I2
J 0
(-6602 3200);
DISPLAY 0.872340 (-6602 3200);
PAINT GREEN (-6602 3200);
DISPLAY INVISIBLE (-6602 3200);
FORCEADD TAP..1
(-2075 3275);
FORCEPROP 3 LASTPIN (-2125 3275) SIG_NAME P5E_CPU1_P3_RX_DP<0>
J 0
(-2115 3285);
DISPLAY 0.659574 (-2115 3285);
PAINT MONO (-2115 3285);
DISPLAY INVISIBLE (-2115 3285);
FORCEPROP 1 LASTPIN (-2125 3275) BN 0
J 0
(-2137 3283);
DISPLAY 0.680851 (-2137 3283);
PAINT GREEN (-2137 3283);
FORCEPROP 2 LAST CDS_LIB standard
J 0
(-2075 3275);
DISPLAY INVISIBLE (-2075 3275);
FORCEPROP 1 LAST BODY_TYPE PLUMBING
J 0
(-2075 3325);
DISPLAY 0.872340 (-2075 3325);
PAINT GREEN (-2075 3325);
DISPLAY INVISIBLE (-2075 3325);
FORCEPROP 1 LAST HDL_TAP TRUE
J 0
(-1750 3150);
DISPLAY 0.872340 (-1750 3150);
DISPLAY INVISIBLE (-1750 3150);
FORCEPROP 1 LAST PATH I20
J 0
(-2077 3275);
DISPLAY 0.872340 (-2077 3275);
PAINT GREEN (-2077 3275);
DISPLAY INVISIBLE (-2077 3275);
FORCEADD TAP..1
(-1875 3175);
FORCEPROP 3 LASTPIN (-1925 3175) SIG_NAME P5E_CPU1_P3_RX_DN<0>
J 0
(-1915 3185);
DISPLAY 0.659574 (-1915 3185);
PAINT MONO (-1915 3185);
DISPLAY INVISIBLE (-1915 3185);
FORCEPROP 1 LASTPIN (-1925 3175) BN 0
J 0
(-1937 3183);
DISPLAY 0.680851 (-1937 3183);
PAINT GREEN (-1937 3183);
FORCEPROP 2 LAST CDS_LIB standard
J 0
(-1875 3175);
DISPLAY INVISIBLE (-1875 3175);
FORCEPROP 1 LAST BODY_TYPE PLUMBING
J 0
(-1875 3225);
DISPLAY 0.872340 (-1875 3225);
PAINT GREEN (-1875 3225);
DISPLAY INVISIBLE (-1875 3225);
FORCEPROP 1 LAST HDL_TAP TRUE
J 0
(-1550 3050);
DISPLAY 0.872340 (-1550 3050);
DISPLAY INVISIBLE (-1550 3050);
FORCEPROP 1 LAST PATH I21
J 0
(-1877 3175);
DISPLAY 0.872340 (-1877 3175);
PAINT GREEN (-1877 3175);
DISPLAY INVISIBLE (-1877 3175);
FORCEADD TAP..1
(-1875 3525);
FORCEPROP 3 LASTPIN (-1925 3525) SIG_NAME P5E_CPU1_P3_RX_DN<1>
J 0
(-1915 3535);
DISPLAY 0.659574 (-1915 3535);
PAINT MONO (-1915 3535);
DISPLAY INVISIBLE (-1915 3535);
FORCEPROP 1 LASTPIN (-1925 3525) BN 1
J 0
(-1937 3533);
DISPLAY 0.680851 (-1937 3533);
PAINT GREEN (-1937 3533);
FORCEPROP 2 LAST CDS_LIB standard
J 0
(-1875 3525);
DISPLAY INVISIBLE (-1875 3525);
FORCEPROP 1 LAST BODY_TYPE PLUMBING
J 0
(-1875 3575);
DISPLAY 0.872340 (-1875 3575);
PAINT GREEN (-1875 3575);
DISPLAY INVISIBLE (-1875 3575);
FORCEPROP 1 LAST HDL_TAP TRUE
J 0
(-1550 3400);
DISPLAY 0.872340 (-1550 3400);
DISPLAY INVISIBLE (-1550 3400);
FORCEPROP 1 LAST PATH I22
J 0
(-1877 3525);
DISPLAY 0.872340 (-1877 3525);
PAINT GREEN (-1877 3525);
DISPLAY INVISIBLE (-1877 3525);
FORCEADD TAP..1
(-1875 3875);
FORCEPROP 3 LASTPIN (-1925 3875) SIG_NAME P5E_CPU1_P3_RX_DN<2>
J 0
(-1915 3885);
DISPLAY 0.659574 (-1915 3885);
PAINT MONO (-1915 3885);
DISPLAY INVISIBLE (-1915 3885);
FORCEPROP 1 LASTPIN (-1925 3875) BN 2
J 0
(-1937 3883);
DISPLAY 0.680851 (-1937 3883);
PAINT GREEN (-1937 3883);
FORCEPROP 2 LAST CDS_LIB standard
J 0
(-1875 3875);
DISPLAY INVISIBLE (-1875 3875);
FORCEPROP 1 LAST BODY_TYPE PLUMBING
J 0
(-1875 3925);
DISPLAY 0.872340 (-1875 3925);
PAINT GREEN (-1875 3925);
DISPLAY INVISIBLE (-1875 3925);
FORCEPROP 1 LAST HDL_TAP TRUE
J 0
(-1550 3750);
DISPLAY 0.872340 (-1550 3750);
DISPLAY INVISIBLE (-1550 3750);
FORCEPROP 1 LAST PATH I23
J 0
(-1877 3875);
DISPLAY 0.872340 (-1877 3875);
PAINT GREEN (-1877 3875);
DISPLAY INVISIBLE (-1877 3875);
FORCEADD TAP..1
(-2075 3975);
FORCEPROP 3 LASTPIN (-2125 3975) SIG_NAME P5E_CPU1_P3_RX_DP<2>
J 0
(-2115 3985);
DISPLAY 0.659574 (-2115 3985);
PAINT MONO (-2115 3985);
DISPLAY INVISIBLE (-2115 3985);
FORCEPROP 1 LASTPIN (-2125 3975) BN 2
J 0
(-2137 3983);
DISPLAY 0.680851 (-2137 3983);
PAINT GREEN (-2137 3983);
FORCEPROP 2 LAST CDS_LIB standard
J 0
(-2075 3975);
DISPLAY INVISIBLE (-2075 3975);
FORCEPROP 1 LAST BODY_TYPE PLUMBING
J 0
(-2075 4025);
DISPLAY 0.872340 (-2075 4025);
PAINT GREEN (-2075 4025);
DISPLAY INVISIBLE (-2075 4025);
FORCEPROP 1 LAST HDL_TAP TRUE
J 0
(-1750 3850);
DISPLAY 0.872340 (-1750 3850);
DISPLAY INVISIBLE (-1750 3850);
FORCEPROP 1 LAST PATH I24
J 0
(-2077 3975);
DISPLAY 0.872340 (-2077 3975);
PAINT GREEN (-2077 3975);
DISPLAY INVISIBLE (-2077 3975);
FORCEADD TAP..1
(-2075 4325);
FORCEPROP 3 LASTPIN (-2125 4325) SIG_NAME P5E_CPU1_P3_RX_DP<3>
J 0
(-2115 4335);
DISPLAY 0.659574 (-2115 4335);
PAINT MONO (-2115 4335);
DISPLAY INVISIBLE (-2115 4335);
FORCEPROP 1 LASTPIN (-2125 4325) BN 3
J 0
(-2137 4333);
DISPLAY 0.680851 (-2137 4333);
PAINT GREEN (-2137 4333);
FORCEPROP 2 LAST CDS_LIB standard
J 0
(-2075 4325);
DISPLAY INVISIBLE (-2075 4325);
FORCEPROP 1 LAST BODY_TYPE PLUMBING
J 0
(-2075 4375);
DISPLAY 0.872340 (-2075 4375);
PAINT GREEN (-2075 4375);
DISPLAY INVISIBLE (-2075 4375);
FORCEPROP 1 LAST HDL_TAP TRUE
J 0
(-1750 4200);
DISPLAY 0.872340 (-1750 4200);
DISPLAY INVISIBLE (-1750 4200);
FORCEPROP 1 LAST PATH I25
J 0
(-2077 4325);
DISPLAY 0.872340 (-2077 4325);
PAINT GREEN (-2077 4325);
DISPLAY INVISIBLE (-2077 4325);
FORCEADD TAP..1
(-1875 4225);
FORCEPROP 3 LASTPIN (-1925 4225) SIG_NAME P5E_CPU1_P3_RX_DN<3>
J 0
(-1915 4235);
DISPLAY 0.659574 (-1915 4235);
PAINT MONO (-1915 4235);
DISPLAY INVISIBLE (-1915 4235);
FORCEPROP 1 LASTPIN (-1925 4225) BN 3
J 0
(-1937 4233);
DISPLAY 0.680851 (-1937 4233);
PAINT GREEN (-1937 4233);
FORCEPROP 2 LAST CDS_LIB standard
J 0
(-1875 4225);
DISPLAY INVISIBLE (-1875 4225);
FORCEPROP 1 LAST BODY_TYPE PLUMBING
J 0
(-1875 4275);
DISPLAY 0.872340 (-1875 4275);
PAINT GREEN (-1875 4275);
DISPLAY INVISIBLE (-1875 4275);
FORCEPROP 1 LAST HDL_TAP TRUE
J 0
(-1550 4100);
DISPLAY 0.872340 (-1550 4100);
DISPLAY INVISIBLE (-1550 4100);
FORCEPROP 1 LAST PATH I26
J 0
(-1877 4225);
DISPLAY 0.872340 (-1877 4225);
PAINT GREEN (-1877 4225);
DISPLAY INVISIBLE (-1877 4225);
FORCEADD TAP..1
(-1875 4575);
FORCEPROP 3 LASTPIN (-1925 4575) SIG_NAME P5E_CPU1_P3_RX_DN<4>
J 0
(-1915 4585);
DISPLAY 0.659574 (-1915 4585);
PAINT MONO (-1915 4585);
DISPLAY INVISIBLE (-1915 4585);
FORCEPROP 1 LASTPIN (-1925 4575) BN 4
J 0
(-1937 4583);
DISPLAY 0.680851 (-1937 4583);
PAINT GREEN (-1937 4583);
FORCEPROP 2 LAST CDS_LIB standard
J 0
(-1875 4575);
DISPLAY INVISIBLE (-1875 4575);
FORCEPROP 1 LAST BODY_TYPE PLUMBING
J 0
(-1875 4625);
DISPLAY 0.872340 (-1875 4625);
PAINT GREEN (-1875 4625);
DISPLAY INVISIBLE (-1875 4625);
FORCEPROP 1 LAST HDL_TAP TRUE
J 0
(-1550 4450);
DISPLAY 0.872340 (-1550 4450);
DISPLAY INVISIBLE (-1550 4450);
FORCEPROP 1 LAST PATH I27
J 0
(-1877 4575);
DISPLAY 0.872340 (-1877 4575);
PAINT GREEN (-1877 4575);
DISPLAY INVISIBLE (-1877 4575);
FORCEADD TAP..1
(-2075 4675);
FORCEPROP 3 LASTPIN (-2125 4675) SIG_NAME P5E_CPU1_P3_RX_DP<4>
J 0
(-2115 4685);
DISPLAY 0.659574 (-2115 4685);
PAINT MONO (-2115 4685);
DISPLAY INVISIBLE (-2115 4685);
FORCEPROP 1 LASTPIN (-2125 4675) BN 4
J 0
(-2137 4683);
DISPLAY 0.680851 (-2137 4683);
PAINT GREEN (-2137 4683);
FORCEPROP 2 LAST CDS_LIB standard
J 0
(-2075 4675);
DISPLAY INVISIBLE (-2075 4675);
FORCEPROP 1 LAST BODY_TYPE PLUMBING
J 0
(-2075 4725);
DISPLAY 0.872340 (-2075 4725);
PAINT GREEN (-2075 4725);
DISPLAY INVISIBLE (-2075 4725);
FORCEPROP 1 LAST HDL_TAP TRUE
J 0
(-1750 4550);
DISPLAY 0.872340 (-1750 4550);
DISPLAY INVISIBLE (-1750 4550);
FORCEPROP 1 LAST PATH I28
J 0
(-2077 4675);
DISPLAY 0.872340 (-2077 4675);
PAINT GREEN (-2077 4675);
DISPLAY INVISIBLE (-2077 4675);
FORCEADD TAP..1
(-2075 5025);
FORCEPROP 3 LASTPIN (-2125 5025) SIG_NAME P5E_CPU1_P3_RX_DP<5>
J 0
(-2115 5035);
DISPLAY 0.659574 (-2115 5035);
PAINT MONO (-2115 5035);
DISPLAY INVISIBLE (-2115 5035);
FORCEPROP 1 LASTPIN (-2125 5025) BN 5
J 0
(-2137 5033);
DISPLAY 0.680851 (-2137 5033);
PAINT GREEN (-2137 5033);
FORCEPROP 2 LAST CDS_LIB standard
J 0
(-2075 5025);
DISPLAY INVISIBLE (-2075 5025);
FORCEPROP 1 LAST BODY_TYPE PLUMBING
J 0
(-2075 5075);
DISPLAY 0.872340 (-2075 5075);
PAINT GREEN (-2075 5075);
DISPLAY INVISIBLE (-2075 5075);
FORCEPROP 1 LAST HDL_TAP TRUE
J 0
(-1750 4900);
DISPLAY 0.872340 (-1750 4900);
DISPLAY INVISIBLE (-1750 4900);
FORCEPROP 1 LAST PATH I29
J 0
(-2077 5025);
DISPLAY 0.872340 (-2077 5025);
PAINT GREEN (-2077 5025);
DISPLAY INVISIBLE (-2077 5025);
FORCEADD TAP..1
(-6600 3550);
FORCEPROP 3 LASTPIN (-6650 3550) SIG_NAME P5E_CPU1_P3_RX_DP<9>
J 0
(-6640 3560);
DISPLAY 0.659574 (-6640 3560);
PAINT MONO (-6640 3560);
DISPLAY INVISIBLE (-6640 3560);
FORCEPROP 1 LASTPIN (-6650 3550) BN 9
J 0
(-6662 3558);
DISPLAY 0.680851 (-6662 3558);
PAINT GREEN (-6662 3558);
FORCEPROP 2 LAST CDS_LIB standard
J 0
(-6600 3550);
DISPLAY INVISIBLE (-6600 3550);
FORCEPROP 1 LAST BODY_TYPE PLUMBING
J 0
(-6600 3600);
DISPLAY 0.872340 (-6600 3600);
PAINT GREEN (-6600 3600);
DISPLAY INVISIBLE (-6600 3600);
FORCEPROP 1 LAST HDL_TAP TRUE
J 0
(-6275 3425);
DISPLAY 0.872340 (-6275 3425);
DISPLAY INVISIBLE (-6275 3425);
FORCEPROP 1 LAST PATH I3
J 0
(-6602 3550);
DISPLAY 0.872340 (-6602 3550);
PAINT GREEN (-6602 3550);
DISPLAY INVISIBLE (-6602 3550);
FORCEADD TAP..1
(-1875 4925);
FORCEPROP 3 LASTPIN (-1925 4925) SIG_NAME P5E_CPU1_P3_RX_DN<5>
J 0
(-1915 4935);
DISPLAY 0.659574 (-1915 4935);
PAINT MONO (-1915 4935);
DISPLAY INVISIBLE (-1915 4935);
FORCEPROP 1 LASTPIN (-1925 4925) BN 5
J 0
(-1937 4933);
DISPLAY 0.680851 (-1937 4933);
PAINT GREEN (-1937 4933);
FORCEPROP 2 LAST CDS_LIB standard
J 0
(-1875 4925);
DISPLAY INVISIBLE (-1875 4925);
FORCEPROP 1 LAST BODY_TYPE PLUMBING
J 0
(-1875 4975);
DISPLAY 0.872340 (-1875 4975);
PAINT GREEN (-1875 4975);
DISPLAY INVISIBLE (-1875 4975);
FORCEPROP 1 LAST HDL_TAP TRUE
J 0
(-1550 4800);
DISPLAY 0.872340 (-1550 4800);
DISPLAY INVISIBLE (-1550 4800);
FORCEPROP 1 LAST PATH I30
J 0
(-1877 4925);
DISPLAY 0.872340 (-1877 4925);
PAINT GREEN (-1877 4925);
DISPLAY INVISIBLE (-1877 4925);
FORCEADD TAP..1
(-2075 5375);
FORCEPROP 3 LASTPIN (-2125 5375) SIG_NAME P5E_CPU1_P3_RX_DP<6>
J 0
(-2115 5385);
DISPLAY 0.659574 (-2115 5385);
PAINT MONO (-2115 5385);
DISPLAY INVISIBLE (-2115 5385);
FORCEPROP 1 LASTPIN (-2125 5375) BN 6
J 0
(-2137 5383);
DISPLAY 0.680851 (-2137 5383);
PAINT GREEN (-2137 5383);
FORCEPROP 2 LAST CDS_LIB standard
J 0
(-2075 5375);
DISPLAY INVISIBLE (-2075 5375);
FORCEPROP 1 LAST BODY_TYPE PLUMBING
J 0
(-2075 5425);
DISPLAY 0.872340 (-2075 5425);
PAINT GREEN (-2075 5425);
DISPLAY INVISIBLE (-2075 5425);
FORCEPROP 1 LAST HDL_TAP TRUE
J 0
(-1750 5250);
DISPLAY 0.872340 (-1750 5250);
DISPLAY INVISIBLE (-1750 5250);
FORCEPROP 1 LAST PATH I31
J 0
(-2077 5375);
DISPLAY 0.872340 (-2077 5375);
PAINT GREEN (-2077 5375);
DISPLAY INVISIBLE (-2077 5375);
FORCEADD TAP..1
(-1875 5275);
FORCEPROP 3 LASTPIN (-1925 5275) SIG_NAME P5E_CPU1_P3_RX_DN<6>
J 0
(-1915 5285);
DISPLAY 0.659574 (-1915 5285);
PAINT MONO (-1915 5285);
DISPLAY INVISIBLE (-1915 5285);
FORCEPROP 1 LASTPIN (-1925 5275) BN 6
J 0
(-1937 5283);
DISPLAY 0.680851 (-1937 5283);
PAINT GREEN (-1937 5283);
FORCEPROP 2 LAST CDS_LIB standard
J 0
(-1875 5275);
DISPLAY INVISIBLE (-1875 5275);
FORCEPROP 1 LAST BODY_TYPE PLUMBING
J 0
(-1875 5325);
DISPLAY 0.872340 (-1875 5325);
PAINT GREEN (-1875 5325);
DISPLAY INVISIBLE (-1875 5325);
FORCEPROP 1 LAST HDL_TAP TRUE
J 0
(-1550 5150);
DISPLAY 0.872340 (-1550 5150);
DISPLAY INVISIBLE (-1550 5150);
FORCEPROP 1 LAST PATH I32
J 0
(-1877 5275);
DISPLAY 0.872340 (-1877 5275);
PAINT GREEN (-1877 5275);
DISPLAY INVISIBLE (-1877 5275);
FORCEADD TAP..1
(-1875 5625);
FORCEPROP 3 LASTPIN (-1925 5625) SIG_NAME P5E_CPU1_P3_RX_DN<7>
J 0
(-1915 5635);
DISPLAY 0.659574 (-1915 5635);
PAINT MONO (-1915 5635);
DISPLAY INVISIBLE (-1915 5635);
FORCEPROP 1 LASTPIN (-1925 5625) BN 7
J 0
(-1937 5633);
DISPLAY 0.680851 (-1937 5633);
PAINT GREEN (-1937 5633);
FORCEPROP 2 LAST CDS_LIB standard
J 0
(-1875 5625);
DISPLAY INVISIBLE (-1875 5625);
FORCEPROP 1 LAST BODY_TYPE PLUMBING
J 0
(-1875 5675);
DISPLAY 0.872340 (-1875 5675);
PAINT GREEN (-1875 5675);
DISPLAY INVISIBLE (-1875 5675);
FORCEPROP 1 LAST HDL_TAP TRUE
J 0
(-1550 5500);
DISPLAY 0.872340 (-1550 5500);
DISPLAY INVISIBLE (-1550 5500);
FORCEPROP 1 LAST PATH I33
J 0
(-1877 5625);
DISPLAY 0.872340 (-1877 5625);
PAINT GREEN (-1877 5625);
DISPLAY INVISIBLE (-1877 5625);
FORCEADD TAP..1
(-2075 5725);
FORCEPROP 3 LASTPIN (-2125 5725) SIG_NAME P5E_CPU1_P3_RX_DP<7>
J 0
(-2115 5735);
DISPLAY 0.659574 (-2115 5735);
PAINT MONO (-2115 5735);
DISPLAY INVISIBLE (-2115 5735);
FORCEPROP 1 LASTPIN (-2125 5725) BN 7
J 0
(-2137 5733);
DISPLAY 0.680851 (-2137 5733);
PAINT GREEN (-2137 5733);
FORCEPROP 2 LAST CDS_LIB standard
J 0
(-2075 5725);
DISPLAY INVISIBLE (-2075 5725);
FORCEPROP 1 LAST BODY_TYPE PLUMBING
J 0
(-2075 5775);
DISPLAY 0.872340 (-2075 5775);
PAINT GREEN (-2075 5775);
DISPLAY INVISIBLE (-2075 5775);
FORCEPROP 1 LAST HDL_TAP TRUE
J 0
(-1750 5600);
DISPLAY 0.872340 (-1750 5600);
DISPLAY INVISIBLE (-1750 5600);
FORCEPROP 1 LAST PATH I34
J 0
(-2077 5725);
DISPLAY 0.872340 (-2077 5725);
PAINT GREEN (-2077 5725);
DISPLAY INVISIBLE (-2077 5725);
FORCEADD OFFPAGE..5
R 2
(-875 5650);
FORCEPROP 2 LAST $XR0 52 
J 0
(-686 5650);
DISPLAY 0.638298 (-686 5650);
PAINT MONO (-686 5650);
FORCEPROP 2 LAST CDS_LIB standard
J 0
(-875 5650);
DISPLAY INVISIBLE (-875 5650);
FORCEPROP 1 LAST OFFPAGE TRUE
J 2
(-1200 5525);
DISPLAY 0.872340 (-1200 5525);
PAINT GREEN (-1200 5525);
DISPLAY INVISIBLE (-1200 5525);
FORCEPROP 1 LAST COMMENT_BODY TRUE
J 2
(-975 5575);
DISPLAY 0.872340 (-975 5575);
PAINT GREEN (-975 5575);
DISPLAY INVISIBLE (-975 5575);
FORCEPROP 2 LAST PATH I35
J 0
(-700 5725);
DISPLAY 0.680851 (-700 5725);
DISPLAY INVISIBLE (-700 5725);
FORCEADD OFFPAGE..5
R 2
(-875 5750);
FORCEPROP 2 LAST $XR0 52 
J 0
(-686 5750);
DISPLAY 0.638298 (-686 5750);
PAINT MONO (-686 5750);
FORCEPROP 2 LAST CDS_LIB standard
J 0
(-875 5750);
DISPLAY INVISIBLE (-875 5750);
FORCEPROP 1 LAST OFFPAGE TRUE
J 2
(-1200 5625);
DISPLAY 0.872340 (-1200 5625);
PAINT GREEN (-1200 5625);
DISPLAY INVISIBLE (-1200 5625);
FORCEPROP 1 LAST COMMENT_BODY TRUE
J 2
(-975 5675);
DISPLAY 0.872340 (-975 5675);
PAINT GREEN (-975 5675);
DISPLAY INVISIBLE (-975 5675);
FORCEPROP 2 LAST PATH I36
J 0
(-700 5825);
DISPLAY 0.680851 (-700 5825);
DISPLAY INVISIBLE (-700 5825);
FORCEADD TAP..1
(-2075 3625);
FORCEPROP 3 LASTPIN (-2125 3625) SIG_NAME P5E_CPU1_P3_RX_DP<1>
J 0
(-2115 3635);
DISPLAY 0.659574 (-2115 3635);
PAINT MONO (-2115 3635);
DISPLAY INVISIBLE (-2115 3635);
FORCEPROP 1 LASTPIN (-2125 3625) BN 1
J 0
(-2137 3633);
DISPLAY 0.680851 (-2137 3633);
PAINT GREEN (-2137 3633);
FORCEPROP 2 LAST CDS_LIB standard
J 0
(-2075 3625);
DISPLAY INVISIBLE (-2075 3625);
FORCEPROP 1 LAST BODY_TYPE PLUMBING
J 0
(-2075 3675);
DISPLAY 0.872340 (-2075 3675);
PAINT GREEN (-2075 3675);
DISPLAY INVISIBLE (-2075 3675);
FORCEPROP 1 LAST HDL_TAP TRUE
J 0
(-1750 3500);
DISPLAY 0.872340 (-1750 3500);
DISPLAY INVISIBLE (-1750 3500);
FORCEPROP 1 LAST PATH I37
J 0
(-2077 3625);
DISPLAY 0.872340 (-2077 3625);
PAINT GREEN (-2077 3625);
DISPLAY INVISIBLE (-2077 3625);
FORCEADD PT5161LRS..7
(-3100 4475);
FORCEPROP 1 LAST LOCATION U6017
J 0
(-3450 6100);
DISPLAY 0.723404 (-3450 6100);
PAINT GREEN (-3450 6100);
FORCEPROP 0 LAST $SEC 7
J 0
(-3450 6250);
DISPLAY 0.680851 (-3450 6250);
PAINT MONO (-3450 6250);
DISPLAY INVISIBLE (-3450 6250);
FORCEPROP 0 LAST CDS_SEC 7
J 0
(-3450 6250);
DISPLAY 0.680851 (-3450 6250);
DISPLAY INVISIBLE (-3450 6250);
FORCEPROP 0 LASTPIN (-2650 5625) $PN CK29
J 0
(-2640 5635);
DISPLAY 0.680851 (-2640 5635);
PAINT MONO (-2640 5635);
FORCEPROP 0 LASTPIN (-2650 5275) $PN CU29
J 0
(-2640 5285);
DISPLAY 0.680851 (-2640 5285);
PAINT MONO (-2640 5285);
FORCEPROP 0 LASTPIN (-2650 4925) $PN DD29
J 0
(-2640 4935);
DISPLAY 0.680851 (-2640 4935);
PAINT MONO (-2640 4935);
FORCEPROP 0 LASTPIN (-2650 4575) $PN DL29
J 0
(-2640 4585);
DISPLAY 0.680851 (-2640 4585);
PAINT MONO (-2640 4585);
FORCEPROP 0 LASTPIN (-2650 4225) $PN DV29
J 0
(-2640 4235);
DISPLAY 0.680851 (-2640 4235);
PAINT MONO (-2640 4235);
FORCEPROP 0 LASTPIN (-2650 3875) $PN EE29
J 0
(-2640 3885);
DISPLAY 0.680851 (-2640 3885);
PAINT MONO (-2640 3885);
FORCEPROP 0 LASTPIN (-2650 3525) $PN EM29
J 0
(-2640 3535);
DISPLAY 0.680851 (-2640 3535);
PAINT MONO (-2640 3535);
FORCEPROP 0 LASTPIN (-2650 3175) $PN EW29
J 0
(-2640 3185);
DISPLAY 0.680851 (-2640 3185);
PAINT MONO (-2640 3185);
FORCEPROP 0 LASTPIN (-2650 5725) $PN CH26
J 0
(-2640 5735);
DISPLAY 0.680851 (-2640 5735);
PAINT MONO (-2640 5735);
FORCEPROP 0 LASTPIN (-2650 5375) $PN CR26
J 0
(-2640 5385);
DISPLAY 0.680851 (-2640 5385);
PAINT MONO (-2640 5385);
FORCEPROP 0 LASTPIN (-2650 5025) $PN DB26
J 0
(-2640 5035);
DISPLAY 0.680851 (-2640 5035);
PAINT MONO (-2640 5035);
FORCEPROP 0 LASTPIN (-2650 4675) $PN DJ26
J 0
(-2640 4685);
DISPLAY 0.680851 (-2640 4685);
PAINT MONO (-2640 4685);
FORCEPROP 0 LASTPIN (-2650 4325) $PN DT26
J 0
(-2640 4335);
DISPLAY 0.680851 (-2640 4335);
PAINT MONO (-2640 4335);
FORCEPROP 0 LASTPIN (-2650 3975) $PN EC26
J 0
(-2640 3985);
DISPLAY 0.680851 (-2640 3985);
PAINT MONO (-2640 3985);
FORCEPROP 0 LASTPIN (-2650 3625) $PN EK26
J 0
(-2640 3635);
DISPLAY 0.680851 (-2640 3635);
PAINT MONO (-2640 3635);
FORCEPROP 0 LASTPIN (-2650 3275) $PN EU26
J 0
(-2640 3285);
DISPLAY 0.680851 (-2640 3285);
PAINT MONO (-2640 3285);
FORCEPROP 2 LAST VALUE PT5161LRS
J 0
(-3450 6150);
DISPLAY 0.680851 (-3450 6150);
FORCEPROP 2 LAST PART_TYPE SMLF
J 0
(-3450 6200);
DISPLAY 0.680851 (-3450 6200);
FORCEPROP 1 LAST MATERIAL IC
J 0
(-3450 5950);
DISPLAY 0.723404 (-3450 5950);
PAINT GREEN (-3450 5950);
FORCEPROP 1 LAST NEEDS_NO_SIZE TRUE
J 0
(-3100 4475);
DISPLAY 0.723404 (-3100 4475);
PAINT GREEN (-3100 4475);
DISPLAY INVISIBLE (-3100 4475);
FORCEPROP 1 LAST CDS_LMAN_SYM_OUTLINE -350,1450,300,-1400
J 0
(-3100 4475);
DISPLAY 0.468085 (-3100 4475);
PAINT GREEN (-3100 4475);
DISPLAY INVISIBLE (-3100 4475);
FORCEPROP 2 LAST CDS_LIB pure_quanta
J 0
(-3100 4475);
DISPLAY INVISIBLE (-3100 4475);
FORCEPROP 1 LAST PATH I38
J 0
(-3100 4475);
DISPLAY 0.723404 (-3100 4475);
PAINT GREEN (-3100 4475);
DISPLAY INVISIBLE (-3100 4475);
FORCEPROP 1 LAST PART_NUMBER AJ051610U03
J 0
(-3450 6025);
DISPLAY 0.723404 (-3450 6025);
PAINT GREEN (-3450 6025);
DISPLAY INVISIBLE (-3450 6025);
FORCEADD TAP..1
(-6400 3100);
FORCEPROP 3 LASTPIN (-6450 3100) SIG_NAME P5E_CPU1_P3_RX_DN<8>
J 0
(-6440 3110);
DISPLAY 0.659574 (-6440 3110);
PAINT MONO (-6440 3110);
DISPLAY INVISIBLE (-6440 3110);
FORCEPROP 1 LASTPIN (-6450 3100) BN 8
J 0
(-6462 3108);
DISPLAY 0.680851 (-6462 3108);
PAINT GREEN (-6462 3108);
FORCEPROP 2 LAST CDS_LIB standard
J 0
(-6400 3100);
DISPLAY INVISIBLE (-6400 3100);
FORCEPROP 1 LAST BODY_TYPE PLUMBING
J 0
(-6400 3150);
DISPLAY 0.872340 (-6400 3150);
PAINT GREEN (-6400 3150);
DISPLAY INVISIBLE (-6400 3150);
FORCEPROP 1 LAST HDL_TAP TRUE
J 0
(-6075 2975);
DISPLAY 0.872340 (-6075 2975);
DISPLAY INVISIBLE (-6075 2975);
FORCEPROP 1 LAST PATH I4
J 0
(-6402 3100);
DISPLAY 0.872340 (-6402 3100);
PAINT GREEN (-6402 3100);
DISPLAY INVISIBLE (-6402 3100);
FORCEADD TAP..1
(-6400 3450);
FORCEPROP 3 LASTPIN (-6450 3450) SIG_NAME P5E_CPU1_P3_RX_DN<9>
J 0
(-6440 3460);
DISPLAY 0.659574 (-6440 3460);
PAINT MONO (-6440 3460);
DISPLAY INVISIBLE (-6440 3460);
FORCEPROP 1 LASTPIN (-6450 3450) BN 9
J 0
(-6462 3458);
DISPLAY 0.680851 (-6462 3458);
PAINT GREEN (-6462 3458);
FORCEPROP 2 LAST CDS_LIB standard
J 0
(-6400 3450);
DISPLAY INVISIBLE (-6400 3450);
FORCEPROP 1 LAST BODY_TYPE PLUMBING
J 0
(-6400 3500);
DISPLAY 0.872340 (-6400 3500);
PAINT GREEN (-6400 3500);
DISPLAY INVISIBLE (-6400 3500);
FORCEPROP 1 LAST HDL_TAP TRUE
J 0
(-6075 3325);
DISPLAY 0.872340 (-6075 3325);
DISPLAY INVISIBLE (-6075 3325);
FORCEPROP 1 LAST PATH I5
J 0
(-6402 3450);
DISPLAY 0.872340 (-6402 3450);
PAINT GREEN (-6402 3450);
DISPLAY INVISIBLE (-6402 3450);
FORCEADD TAP..1
(-6600 3900);
FORCEPROP 3 LASTPIN (-6650 3900) SIG_NAME P5E_CPU1_P3_RX_DP<10>
J 0
(-6640 3910);
DISPLAY 0.659574 (-6640 3910);
PAINT MONO (-6640 3910);
DISPLAY INVISIBLE (-6640 3910);
FORCEPROP 1 LASTPIN (-6650 3900) BN 10
J 0
(-6662 3908);
DISPLAY 0.680851 (-6662 3908);
PAINT GREEN (-6662 3908);
FORCEPROP 2 LAST CDS_LIB standard
J 0
(-6600 3900);
DISPLAY INVISIBLE (-6600 3900);
FORCEPROP 1 LAST BODY_TYPE PLUMBING
J 0
(-6600 3950);
DISPLAY 0.872340 (-6600 3950);
PAINT GREEN (-6600 3950);
DISPLAY INVISIBLE (-6600 3950);
FORCEPROP 1 LAST HDL_TAP TRUE
J 0
(-6275 3775);
DISPLAY 0.872340 (-6275 3775);
DISPLAY INVISIBLE (-6275 3775);
FORCEPROP 1 LAST PATH I6
J 0
(-6602 3900);
DISPLAY 0.872340 (-6602 3900);
PAINT GREEN (-6602 3900);
DISPLAY INVISIBLE (-6602 3900);
FORCEADD TAP..1
(-6600 4250);
FORCEPROP 3 LASTPIN (-6650 4250) SIG_NAME P5E_CPU1_P3_RX_DP<11>
J 0
(-6640 4260);
DISPLAY 0.659574 (-6640 4260);
PAINT MONO (-6640 4260);
DISPLAY INVISIBLE (-6640 4260);
FORCEPROP 1 LASTPIN (-6650 4250) BN 11
J 0
(-6662 4258);
DISPLAY 0.680851 (-6662 4258);
PAINT GREEN (-6662 4258);
FORCEPROP 2 LAST CDS_LIB standard
J 0
(-6600 4250);
DISPLAY INVISIBLE (-6600 4250);
FORCEPROP 1 LAST BODY_TYPE PLUMBING
J 0
(-6600 4300);
DISPLAY 0.872340 (-6600 4300);
PAINT GREEN (-6600 4300);
DISPLAY INVISIBLE (-6600 4300);
FORCEPROP 1 LAST HDL_TAP TRUE
J 0
(-6275 4125);
DISPLAY 0.872340 (-6275 4125);
DISPLAY INVISIBLE (-6275 4125);
FORCEPROP 1 LAST PATH I7
J 0
(-6602 4250);
DISPLAY 0.872340 (-6602 4250);
PAINT GREEN (-6602 4250);
DISPLAY INVISIBLE (-6602 4250);
FORCEADD TAP..1
(-6600 4600);
FORCEPROP 3 LASTPIN (-6650 4600) SIG_NAME P5E_CPU1_P3_RX_DP<12>
J 0
(-6640 4610);
DISPLAY 0.659574 (-6640 4610);
PAINT MONO (-6640 4610);
DISPLAY INVISIBLE (-6640 4610);
FORCEPROP 1 LASTPIN (-6650 4600) BN 12
J 0
(-6662 4608);
DISPLAY 0.680851 (-6662 4608);
PAINT GREEN (-6662 4608);
FORCEPROP 2 LAST CDS_LIB standard
J 0
(-6600 4600);
DISPLAY INVISIBLE (-6600 4600);
FORCEPROP 1 LAST BODY_TYPE PLUMBING
J 0
(-6600 4650);
DISPLAY 0.872340 (-6600 4650);
PAINT GREEN (-6600 4650);
DISPLAY INVISIBLE (-6600 4650);
FORCEPROP 1 LAST HDL_TAP TRUE
J 0
(-6275 4475);
DISPLAY 0.872340 (-6275 4475);
DISPLAY INVISIBLE (-6275 4475);
FORCEPROP 1 LAST PATH I8
J 0
(-6602 4600);
DISPLAY 0.872340 (-6602 4600);
PAINT GREEN (-6602 4600);
DISPLAY INVISIBLE (-6602 4600);
FORCEADD TAP..1
(-6400 3800);
FORCEPROP 3 LASTPIN (-6450 3800) SIG_NAME P5E_CPU1_P3_RX_DN<10>
J 0
(-6440 3810);
DISPLAY 0.659574 (-6440 3810);
PAINT MONO (-6440 3810);
DISPLAY INVISIBLE (-6440 3810);
FORCEPROP 1 LASTPIN (-6450 3800) BN 10
J 0
(-6462 3808);
DISPLAY 0.680851 (-6462 3808);
PAINT GREEN (-6462 3808);
FORCEPROP 2 LAST CDS_LIB standard
J 0
(-6400 3800);
DISPLAY INVISIBLE (-6400 3800);
FORCEPROP 1 LAST BODY_TYPE PLUMBING
J 0
(-6400 3850);
DISPLAY 0.872340 (-6400 3850);
PAINT GREEN (-6400 3850);
DISPLAY INVISIBLE (-6400 3850);
FORCEPROP 1 LAST HDL_TAP TRUE
J 0
(-6075 3675);
DISPLAY 0.872340 (-6075 3675);
DISPLAY INVISIBLE (-6075 3675);
FORCEPROP 1 LAST PATH I9
J 0
(-6402 3800);
DISPLAY 0.872340 (-6402 3800);
PAINT GREEN (-6402 3800);
DISPLAY INVISIBLE (-6402 3800);
FORCEADD QUANTA_TITLE_BLOCK_C..1
(0 0);
FORCEPROP 0 LAST CDS_CON_LAST_MODIFIED Thu Sep 14 16:12:56 2023
J 0
(-1885 15);
DISPLAY INVISIBLE (-1885 15);
FORCEPROP 1 LAST CUSTOM_TXT_CDS <CON_LAST_MODIFIED>
J 0
(-1885 15);
DISPLAY 0.978723 (-1885 15);
FORCEPROP 2 LAST CUSTOM_TXT_CDS <XR_PAGE_TITLE>
J 0
(-7890 5250);
DISPLAY 0.638298 (-7890 5250);
PAINT PINK (-7890 5250);
DISPLAY INVISIBLE (-7890 5250);
FORCEPROP 1 LAST CUSTOM_TXT_CDS <NAME_2>
J 0
(-3175 50);
FORCEPROP 1 LAST CUSTOM_TXT_CDS <NAME_1>
J 0
(-3175 175);
FORCEPROP 1 LAST CUSTOM_TXT_CDS <Q_NUMBER>
J 0
(-1403 103);
DISPLAY 1.212766 (-1403 103);
FORCEPROP 1 LAST CUSTOM_TXT_CDS <Q_PROJ>
J 0
(-2382 102);
DISPLAY 1.212766 (-2382 102);
FORCEPROP 1 LAST CUSTOM_TXT_CDS <Q_REV>
J 0
(-184 103);
DISPLAY 1.212766 (-184 103);
FORCEPROP 1 LAST CUSTOM_TXT_CDS <CON_PAGE_NUM> OF <CON_TOTAL_PAGES>
J 0
(-446 18);
DISPLAY 0.978723 (-446 18);
FORCEPROP 1 LAST Q_TITLE RETIMER_CPU1_P3(2)
J 0
(-9366 26);
DISPLAY 2.446809 (-9366 26);
PAINT GREEN (-9366 26);
FORCEPROP 2 LAST PAGE_BORDER TRUE
J 0
(-7890 5250);
DISPLAY 0.638298 (-7890 5250);
PAINT PINK (-7890 5250);
DISPLAY INVISIBLE (-7890 5250);
FORCEPROP 1 LAST CDS_LMAN_SYM_OUTLINE -9475,6775,100,-125
J 0
(0 0);
DISPLAY 0.468085 (0 0);
PAINT GREEN (0 0);
DISPLAY INVISIBLE (0 0);
FORCEPROP 2 LAST CDS_LIB pure_quanta
J 0
(0 0);
DISPLAY INVISIBLE (0 0);
FORCEPROP 2 LAST CDS_XR_PAGE_TITLE CR-351 : @T6G_MB_LIB.T6G(SCH_1):PAGE351
J 0
(-7890 5250);
DISPLAY 0.638298 (-7890 5250);
PAINT PINK (-7890 5250);
DISPLAY INVISIBLE (-7890 5250);
FORCEPROP 1 LAST Q_DEPT BU9
J 1
(-3763 49);
DISPLAY 1.957447 (-3763 49);
PAINT GREEN (-3763 49);
DISPLAY INVISIBLE (-3763 49);
FORCEPROP 1 LAST COMMENT_BODY TRUE
J 0
(12 -13);
DISPLAY 0.978723 (12 -13);
PAINT GREEN (12 -13);
DISPLAY INVISIBLE (12 -13);
WIRE 17 -1 (-2025 5400)(-2025 5050);
WIRE 17 -1 (-2025 5750)(-2025 5400);
WIRE 17 -1 (-2025 5050)(-2025 4700);
WIRE 17 -1 (-2025 4350)(-2025 4700);
WIRE 17 -1 (-2025 5750)(-925 5750);
FORCEPROP 2 LAST SIG_NAME P5E_CPU1_P3_RX_DP<7:0>
J 0
(-1760 5760);
DISPLAY 0.680851 (-1760 5760);
PAINT WHITE (-1760 5760);
WIRE 17 -1 (-6550 4275)(-6550 4625);
WIRE 17 -1 (-6550 4275)(-6550 3925);
WIRE 17 -1 (-6550 4975)(-6550 4625);
WIRE 17 -1 (-6550 5325)(-6550 4975);
WIRE 17 -1 (-6550 3925)(-6550 3575);
WIRE 17 -1 (-6550 3575)(-6550 3225);
WIRE 17 -1 (-6550 5675)(-6550 5325);
WIRE 17 -1 (-6550 5750)(-6550 5675);
WIRE 17 -1 (-6550 5750)(-5425 5750);
FORCEPROP 2 LAST SIG_NAME P5E_CPU1_P3_RX_DP<15:8>
J 0
(-6285 5760);
DISPLAY 0.680851 (-6285 5760);
PAINT WHITE (-6285 5760);
WIRE 17 -1 (-2025 4000)(-2025 3650);
WIRE 17 -1 (-2025 4350)(-2025 4000);
WIRE 17 -1 (-2025 3650)(-2025 3300);
WIRE 17 -1 (-1825 5650)(-1825 5300);
WIRE 17 -1 (-1825 5650)(-925 5650);
FORCEPROP 2 LAST SIG_NAME P5E_CPU1_P3_RX_DN<7:0>
J 0
(-1760 5660);
DISPLAY 0.680851 (-1760 5660);
PAINT WHITE (-1760 5660);
WIRE 17 -1 (-1825 3550)(-1825 3200);
WIRE 17 -1 (-1825 3900)(-1825 3550);
WIRE 17 -1 (-1825 4250)(-1825 3900);
WIRE 17 -1 (-1825 4250)(-1825 4600);
WIRE 17 -1 (-1825 4950)(-1825 4600);
WIRE 17 -1 (-1825 5300)(-1825 4950);
WIRE 17 -1 (-6350 3825)(-6350 3475);
WIRE 17 -1 (-6350 4175)(-6350 3825);
WIRE 17 -1 (-6350 3475)(-6350 3125);
WIRE 17 -1 (-6350 4175)(-6350 4525);
WIRE 17 -1 (-6350 4875)(-6350 4525);
WIRE 17 -1 (-6350 5225)(-6350 4875);
WIRE 17 -1 (-6350 5575)(-6350 5225);
WIRE 17 -1 (-6350 5625)(-6350 5575);
WIRE 17 -1 (-6350 5625)(-5450 5625);
FORCEPROP 2 LAST SIG_NAME P5E_CPU1_P3_RX_DN<15:8>
J 0
(-6285 5635);
DISPLAY 0.680851 (-6285 5635);
PAINT WHITE (-6285 5635);
WIRE 16 -1 (-7175 5200)(-6450 5200);
WIRE 16 -1 (-7175 5550)(-6450 5550);
WIRE 16 -1 (-7175 5300)(-6650 5300);
WIRE 16 -1 (-7175 4150)(-6450 4150);
WIRE 16 -1 (-7175 3900)(-6650 3900);
WIRE 16 -1 (-2650 5625)(-1925 5625);
WIRE 16 -1 (-7175 3100)(-6450 3100);
WIRE 16 -1 (-7175 3800)(-6450 3800);
WIRE 16 -1 (-7175 4500)(-6450 4500);
WIRE 16 -1 (-7175 4850)(-6450 4850);
WIRE 16 -1 (-7175 3450)(-6450 3450);
WIRE 16 -1 (-2650 4925)(-1925 4925);
WIRE 16 -1 (-2650 4575)(-1925 4575);
WIRE 16 -1 (-2650 4225)(-1925 4225);
WIRE 16 -1 (-2650 3875)(-1925 3875);
WIRE 16 -1 (-2650 3525)(-1925 3525);
WIRE 16 -1 (-2650 3175)(-1925 3175);
WIRE 16 -1 (-2650 5275)(-1925 5275);
WIRE 16 -1 (-2650 3275)(-2125 3275);
WIRE 16 -1 (-7175 3550)(-6650 3550);
WIRE 16 -1 (-7175 3200)(-6650 3200);
WIRE 16 -1 (-7175 4950)(-6650 4950);
WIRE 16 -1 (-7175 5650)(-6650 5650);
WIRE 16 -1 (-2650 5375)(-2125 5375);
WIRE 16 -1 (-2650 5725)(-2125 5725);
WIRE 16 -1 (-2650 4675)(-2125 4675);
WIRE 16 -1 (-2650 4325)(-2125 4325);
WIRE 16 -1 (-2650 3975)(-2125 3975);
WIRE 16 -1 (-2650 3625)(-2125 3625);
WIRE 16 -1 (-7175 4600)(-6650 4600);
WIRE 16 -1 (-7175 4250)(-6650 4250);
WIRE 16 -1 (-2650 5025)(-2125 5025);
FORCENOTE
RETIMER TO CPU
(-3450 2700) 0;
DISPLAY LEFT (-3450 2700);
DISPLAY 3.148936 (-3450 2700);
FORCENOTE
RETIMER TO CPU
(-7975 2650) 0;
DISPLAY LEFT (-7975 2650);
DISPLAY 3.148936 (-7975 2650);
FORCENOTE
P5E_CPU1_P3_RX_DP/DN<0-15> LANE REVERSAL
(-9100 6300) 0;
DISPLAY LEFT (-9100 6300);
DISPLAY 2.510638 (-9100 6300);
QUIT
